(kicad_pcb
	(version 20260206)
	(generator "pcbnew")
	(generator_version "10.0")
	(general
		(thickness 1.6)
		(legacy_teardrops no)
	)
	(paper "A4")
	(title_block
		(title "04192023_DAF0TMB3IC0_F0TG_MB_C_brd_V02_OCP.brd")
		(comment 1 "Grand Teton / footprint 3579 of 8354 (J30), pads 114-226 of 291")
	)
	(layers
		(0 "F.Cu" signal "TOP")
		(4 "In1.Cu" signal "GND")
		(6 "In2.Cu" signal "IN1")
		(8 "In3.Cu" signal "GND1")
		(10 "In4.Cu" signal "IN2")
		(12 "In5.Cu" signal "GND2")
		(14 "In6.Cu" signal "IN3")
		(16 "In7.Cu" signal "GND3")
		(18 "In8.Cu" signal "VCC")
		(20 "In9.Cu" signal "VCC1")
		(22 "In10.Cu" signal "GND4")
		(24 "In11.Cu" signal "IN4")
		(26 "In12.Cu" signal "GND5")
		(28 "In13.Cu" signal "IN5")
		(30 "In14.Cu" signal "GND6")
		(32 "In15.Cu" signal "IN6")
		(34 "In16.Cu" signal "GND7")
		(2 "B.Cu" signal "BOTTOM")
		(9 "F.Adhes" user "F.Adhesive")
		(11 "B.Adhes" user "B.Adhesive")
		(13 "F.Paste" user "Package Geometry/Pastemask Top")
		(15 "B.Paste" user "Package Geometry/Pastemask Bottom")
		(5 "F.SilkS" user "Ref Des/Silkscreen Top")
		(7 "B.SilkS" user "Ref Des/Silkscreen Bottom")
		(1 "F.Mask" user "Board Geometry/Soldermask Top")
		(3 "B.Mask" user "Board Geometry/Soldermask Bottom")
		(17 "Dwgs.User" user "User.Drawings")
		(19 "Cmts.User" user "User.Comments")
		(21 "Eco1.User" user "User.Eco1")
		(23 "Eco2.User" user "User.Eco2")
		(25 "Edge.Cuts" user "Board Geometry/Outline")
		(27 "Margin" user)
		(31 "F.CrtYd" user "Package Geometry/Place Bound Top")
		(29 "B.CrtYd" user "Package Geometry/Place Bound Bottom")
		(35 "F.Fab" user "Ref Des/Assembly Top")
		(33 "B.Fab" user "Ref Des/Assembly Bottom")
	)
	(footprint ""
		(layer "F.Cu")
		(at 34.74593 -255.560322 180)
		(property "Reference" "J30"
			(at 3.12293 -81.850992 0)
			(unlocked yes)
			(layer "F.SilkS")
			(effects
				(font
					(size 0.7874 0.5842)
					(thickness 0.1524)
				)
			)
		)
		(property "Value" ""
			(at 0 0 180)
			(layer "F.Fab")
			(effects
				(font
					(size 1.27 1.27)
				)
			)
		)
		(duplicate_pad_numbers_are_jumpers no)
		(pad "114" smd rect
			(at -2.050034 37.824918 90)
			(size 0.519938 1.4986)
			(layers "F.Cu" "F.Mask" "F.Paste")
			(net "GND")
		)
		(pad "115" smd rect
			(at -2.050034 38.675056 90)
			(size 0.519938 1.4986)
			(layers "F.Cu" "F.Mask" "F.Paste")
			(net "M_D_CPU1_SB_DQS_DP<1>")
		)
		(pad "116" smd rect
			(at -2.050034 39.52494 90)
			(size 0.519938 1.4986)
			(layers "F.Cu" "F.Mask" "F.Paste")
			(net "M_D_CPU1_SB_DQS_DN<1>")
		)
		(pad "117" smd rect
			(at -2.050034 40.375078 90)
			(size 0.519938 1.4986)
			(layers "F.Cu" "F.Mask" "F.Paste")
			(net "GND")
		)
		(pad "118" smd rect
			(at -2.050034 41.224962 90)
			(size 0.519938 1.4986)
			(layers "F.Cu" "F.Mask" "F.Paste")
			(net "M_D_CPU1_SB_DQ<12>")
		)
		(pad "119" smd rect
			(at -2.050034 42.0751 90)
			(size 0.519938 1.4986)
			(layers "F.Cu" "F.Mask" "F.Paste")
			(net "GND")
		)
		(pad "120" smd rect
			(at -2.050034 42.924984 90)
			(size 0.519938 1.4986)
			(layers "F.Cu" "F.Mask" "F.Paste")
			(net "M_D_CPU1_SB_DQ<13>")
		)
		(pad "121" smd rect
			(at -2.050034 43.775122 90)
			(size 0.519938 1.4986)
			(layers "F.Cu" "F.Mask" "F.Paste")
			(net "GND")
		)
		(pad "122" smd rect
			(at -2.050034 44.625006 90)
			(size 0.519938 1.4986)
			(layers "F.Cu" "F.Mask" "F.Paste")
			(net "M_D_CPU1_SB_DQ<16>")
		)
		(pad "123" smd rect
			(at -2.050034 45.47489 90)
			(size 0.519938 1.4986)
			(layers "F.Cu" "F.Mask" "F.Paste")
			(net "GND")
		)
		(pad "124" smd rect
			(at -2.050034 46.325028 90)
			(size 0.519938 1.4986)
			(layers "F.Cu" "F.Mask" "F.Paste")
			(net "M_D_CPU1_SB_DQ<17>")
		)
		(pad "125" smd rect
			(at -2.050034 47.174912 90)
			(size 0.519938 1.4986)
			(layers "F.Cu" "F.Mask" "F.Paste")
			(net "GND")
		)
		(pad "126" smd rect
			(at -2.050034 48.02505 90)
			(size 0.519938 1.4986)
			(layers "F.Cu" "F.Mask" "F.Paste")
			(net "M_D_CPU1_SB_DQS_DP<2>")
		)
		(pad "127" smd rect
			(at -2.050034 48.874934 90)
			(size 0.519938 1.4986)
			(layers "F.Cu" "F.Mask" "F.Paste")
			(net "M_D_CPU1_SB_DQS_DN<2>")
		)
		(pad "128" smd rect
			(at -2.050034 49.725072 90)
			(size 0.519938 1.4986)
			(layers "F.Cu" "F.Mask" "F.Paste")
			(net "GND")
		)
		(pad "129" smd rect
			(at -2.050034 50.574956 90)
			(size 0.519938 1.4986)
			(layers "F.Cu" "F.Mask" "F.Paste")
			(net "M_D_CPU1_SB_DQ<20>")
		)
		(pad "130" smd rect
			(at -2.050034 51.425094 90)
			(size 0.519938 1.4986)
			(layers "F.Cu" "F.Mask" "F.Paste")
			(net "GND")
		)
		(pad "131" smd rect
			(at -2.050034 52.274978 90)
			(size 0.519938 1.4986)
			(layers "F.Cu" "F.Mask" "F.Paste")
			(net "M_D_CPU1_SB_DQ<21>")
		)
		(pad "132" smd rect
			(at -2.050034 53.125116 90)
			(size 0.519938 1.4986)
			(layers "F.Cu" "F.Mask" "F.Paste")
			(net "GND")
		)
		(pad "133" smd rect
			(at -2.050034 53.975 90)
			(size 0.519938 1.4986)
			(layers "F.Cu" "F.Mask" "F.Paste")
			(net "M_D_CPU1_SB_DQ<24>")
		)
		(pad "134" smd rect
			(at -2.050034 54.824884 90)
			(size 0.519938 1.4986)
			(layers "F.Cu" "F.Mask" "F.Paste")
			(net "GND")
		)
		(pad "135" smd rect
			(at -2.050034 55.675022 90)
			(size 0.519938 1.4986)
			(layers "F.Cu" "F.Mask" "F.Paste")
			(net "M_D_CPU1_SB_DQ<25>")
		)
		(pad "136" smd rect
			(at -2.050034 56.524906 90)
			(size 0.519938 1.4986)
			(layers "F.Cu" "F.Mask" "F.Paste")
			(net "GND")
		)
		(pad "137" smd rect
			(at -2.050034 57.375044 90)
			(size 0.519938 1.4986)
			(layers "F.Cu" "F.Mask" "F.Paste")
			(net "M_D_CPU1_SB_DQS_DP<3>")
		)
		(pad "138" smd rect
			(at -2.050034 58.224928 90)
			(size 0.519938 1.4986)
			(layers "F.Cu" "F.Mask" "F.Paste")
			(net "M_D_CPU1_SB_DQS_DN<3>")
		)
		(pad "139" smd rect
			(at -2.050034 59.075066 90)
			(size 0.519938 1.4986)
			(layers "F.Cu" "F.Mask" "F.Paste")
			(net "GND")
		)
		(pad "140" smd rect
			(at -2.050034 59.92495 90)
			(size 0.519938 1.4986)
			(layers "F.Cu" "F.Mask" "F.Paste")
			(net "M_D_CPU1_SB_DQ<28>")
		)
		(pad "141" smd rect
			(at -2.050034 60.775088 90)
			(size 0.519938 1.4986)
			(layers "F.Cu" "F.Mask" "F.Paste")
			(net "GND")
		)
		(pad "142" smd rect
			(at -2.050034 61.624972 90)
			(size 0.519938 1.4986)
			(layers "F.Cu" "F.Mask" "F.Paste")
			(net "M_D_CPU1_SB_DQ<29>")
		)
		(pad "143" smd rect
			(at -2.050034 62.47511 90)
			(size 0.519938 1.4986)
			(layers "F.Cu" "F.Mask" "F.Paste")
			(net "GND")
		)
		(pad "144" smd rect
			(at -2.050034 63.324994 90)
			(size 0.519938 1.4986)
			(layers "F.Cu" "F.Mask" "F.Paste")
			(net "Net_2299")
		)
		(pad "145" smd rect
			(at 2.050034 -63.324994 90)
			(size 0.519938 1.4986)
			(layers "F.Cu" "F.Mask" "F.Paste")
			(net "P12V_MEM_CPU1")
		)
		(pad "146" smd rect
			(at 2.050034 -62.47511 90)
			(size 0.519938 1.4986)
			(layers "F.Cu" "F.Mask" "F.Paste")
			(net "P12V_MEM_CPU1")
		)
		(pad "147" smd rect
			(at 2.050034 -61.624972 90)
			(size 0.519938 1.4986)
			(layers "F.Cu" "F.Mask" "F.Paste")
			(net "PWRGD_CHD_CPU1_DIMM")
		)
		(pad "148" smd rect
			(at 2.050034 -60.775088 90)
			(size 0.519938 1.4986)
			(layers "F.Cu" "F.Mask" "F.Paste")
			(net "PD_CHD_CPU1_DIMM_SAA")
		)
		(pad "149" smd rect
			(at 2.050034 -59.92495 90)
			(size 0.519938 1.4986)
			(layers "F.Cu" "F.Mask" "F.Paste")
			(net "Net_2300")
		)
		(pad "150" smd rect
			(at 2.050034 -59.075066 90)
			(size 0.519938 1.4986)
			(layers "F.Cu" "F.Mask" "F.Paste")
			(net "Net_2301")
		)
		(pad "151" smd rect
			(at 2.050034 -58.224928 90)
			(size 0.519938 1.4986)
			(layers "F.Cu" "F.Mask" "F.Paste")
			(net "GND")
		)
		(pad "152" smd rect
			(at 2.050034 -57.375044 90)
			(size 0.519938 1.4986)
			(layers "F.Cu" "F.Mask" "F.Paste")
			(net "M_D_CPU1_SA_DQ<2>")
		)
		(pad "153" smd rect
			(at 2.050034 -56.524906 90)
			(size 0.519938 1.4986)
			(layers "F.Cu" "F.Mask" "F.Paste")
			(net "GND")
		)
		(pad "154" smd rect
			(at 2.050034 -55.675022 90)
			(size 0.519938 1.4986)
			(layers "F.Cu" "F.Mask" "F.Paste")
			(net "M_D_CPU1_SA_DQ<3>")
		)
		(pad "155" smd rect
			(at 2.050034 -54.824884 90)
			(size 0.519938 1.4986)
			(layers "F.Cu" "F.Mask" "F.Paste")
			(net "GND")
		)
		(pad "156" smd rect
			(at 2.050034 -53.975 90)
			(size 0.519938 1.4986)
			(layers "F.Cu" "F.Mask" "F.Paste")
			(net "M_D_CPU1_SA_DQS_DN<5>")
		)
		(pad "157" smd rect
			(at 2.050034 -53.125116 90)
			(size 0.519938 1.4986)
			(layers "F.Cu" "F.Mask" "F.Paste")
			(net "M_D_CPU1_SA_DQS_DP<5>")
		)
		(pad "158" smd rect
			(at 2.050034 -52.274978 90)
			(size 0.519938 1.4986)
			(layers "F.Cu" "F.Mask" "F.Paste")
			(net "GND")
		)
		(pad "159" smd rect
			(at 2.050034 -51.425094 90)
			(size 0.519938 1.4986)
			(layers "F.Cu" "F.Mask" "F.Paste")
			(net "M_D_CPU1_SA_DQ<6>")
		)
		(pad "160" smd rect
			(at 2.050034 -50.574956 90)
			(size 0.519938 1.4986)
			(layers "F.Cu" "F.Mask" "F.Paste")
			(net "GND")
		)
		(pad "161" smd rect
			(at 2.050034 -49.725072 90)
			(size 0.519938 1.4986)
			(layers "F.Cu" "F.Mask" "F.Paste")
			(net "M_D_CPU1_SA_DQ<7>")
		)
		(pad "162" smd rect
			(at 2.050034 -48.874934 90)
			(size 0.519938 1.4986)
			(layers "F.Cu" "F.Mask" "F.Paste")
			(net "GND")
		)
		(pad "163" smd rect
			(at 2.050034 -48.02505 90)
			(size 0.519938 1.4986)
			(layers "F.Cu" "F.Mask" "F.Paste")
			(net "M_D_CPU1_SA_DQ<10>")
		)
		(pad "164" smd rect
			(at 2.050034 -47.174912 90)
			(size 0.519938 1.4986)
			(layers "F.Cu" "F.Mask" "F.Paste")
			(net "GND")
		)
		(pad "165" smd rect
			(at 2.050034 -46.325028 90)
			(size 0.519938 1.4986)
			(layers "F.Cu" "F.Mask" "F.Paste")
			(net "M_D_CPU1_SA_DQ<11>")
		)
		(pad "166" smd rect
			(at 2.050034 -45.47489 90)
			(size 0.519938 1.4986)
			(layers "F.Cu" "F.Mask" "F.Paste")
			(net "GND")
		)
		(pad "167" smd rect
			(at 2.050034 -44.625006 90)
			(size 0.519938 1.4986)
			(layers "F.Cu" "F.Mask" "F.Paste")
			(net "M_D_CPU1_SA_DQS_DN<6>")
		)
		(pad "168" smd rect
			(at 2.050034 -43.775122 90)
			(size 0.519938 1.4986)
			(layers "F.Cu" "F.Mask" "F.Paste")
			(net "M_D_CPU1_SA_DQS_DP<6>")
		)
		(pad "169" smd rect
			(at 2.050034 -42.924984 90)
			(size 0.519938 1.4986)
			(layers "F.Cu" "F.Mask" "F.Paste")
			(net "GND")
		)
		(pad "170" smd rect
			(at 2.050034 -42.0751 90)
			(size 0.519938 1.4986)
			(layers "F.Cu" "F.Mask" "F.Paste")
			(net "M_D_CPU1_SA_DQ<14>")
		)
		(pad "171" smd rect
			(at 2.050034 -41.224962 90)
			(size 0.519938 1.4986)
			(layers "F.Cu" "F.Mask" "F.Paste")
			(net "GND")
		)
		(pad "172" smd rect
			(at 2.050034 -40.375078 90)
			(size 0.519938 1.4986)
			(layers "F.Cu" "F.Mask" "F.Paste")
			(net "M_D_CPU1_SA_DQ<15>")
		)
		(pad "173" smd rect
			(at 2.050034 -39.52494 90)
			(size 0.519938 1.4986)
			(layers "F.Cu" "F.Mask" "F.Paste")
			(net "GND")
		)
		(pad "174" smd rect
			(at 2.050034 -38.675056 90)
			(size 0.519938 1.4986)
			(layers "F.Cu" "F.Mask" "F.Paste")
			(net "M_D_CPU1_SA_DQ<18>")
		)
		(pad "175" smd rect
			(at 2.050034 -37.824918 90)
			(size 0.519938 1.4986)
			(layers "F.Cu" "F.Mask" "F.Paste")
			(net "GND")
		)
		(pad "176" smd rect
			(at 2.050034 -36.975034 90)
			(size 0.519938 1.4986)
			(layers "F.Cu" "F.Mask" "F.Paste")
			(net "M_D_CPU1_SA_DQ<19>")
		)
		(pad "177" smd rect
			(at 2.050034 -36.124896 90)
			(size 0.519938 1.4986)
			(layers "F.Cu" "F.Mask" "F.Paste")
			(net "GND")
		)
		(pad "178" smd rect
			(at 2.050034 -35.275012 90)
			(size 0.519938 1.4986)
			(layers "F.Cu" "F.Mask" "F.Paste")
			(net "M_D_CPU1_SA_DQS_DN<7>")
		)
		(pad "179" smd rect
			(at 2.050034 -34.425128 90)
			(size 0.519938 1.4986)
			(layers "F.Cu" "F.Mask" "F.Paste")
			(net "M_D_CPU1_SA_DQS_DP<7>")
		)
		(pad "180" smd rect
			(at 2.050034 -33.57499 90)
			(size 0.519938 1.4986)
			(layers "F.Cu" "F.Mask" "F.Paste")
			(net "GND")
		)
		(pad "181" smd rect
			(at 2.050034 -32.725106 90)
			(size 0.519938 1.4986)
			(layers "F.Cu" "F.Mask" "F.Paste")
			(net "M_D_CPU1_SA_DQ<22>")
		)
		(pad "182" smd rect
			(at 2.050034 -31.874968 90)
			(size 0.519938 1.4986)
			(layers "F.Cu" "F.Mask" "F.Paste")
			(net "GND")
		)
		(pad "183" smd rect
			(at 2.050034 -31.025084 90)
			(size 0.519938 1.4986)
			(layers "F.Cu" "F.Mask" "F.Paste")
			(net "M_D_CPU1_SA_DQ<23>")
		)
		(pad "184" smd rect
			(at 2.050034 -30.174946 90)
			(size 0.519938 1.4986)
			(layers "F.Cu" "F.Mask" "F.Paste")
			(net "GND")
		)
		(pad "185" smd rect
			(at 2.050034 -29.325062 90)
			(size 0.519938 1.4986)
			(layers "F.Cu" "F.Mask" "F.Paste")
			(net "M_D_CPU1_SA_DQ<26>")
		)
		(pad "186" smd rect
			(at 2.050034 -28.474924 90)
			(size 0.519938 1.4986)
			(layers "F.Cu" "F.Mask" "F.Paste")
			(net "GND")
		)
		(pad "187" smd rect
			(at 2.050034 -27.62504 90)
			(size 0.519938 1.4986)
			(layers "F.Cu" "F.Mask" "F.Paste")
			(net "M_D_CPU1_SA_DQ<27>")
		)
		(pad "188" smd rect
			(at 2.050034 -26.774902 90)
			(size 0.519938 1.4986)
			(layers "F.Cu" "F.Mask" "F.Paste")
			(net "GND")
		)
		(pad "189" smd rect
			(at 2.050034 -25.925018 90)
			(size 0.519938 1.4986)
			(layers "F.Cu" "F.Mask" "F.Paste")
			(net "M_D_CPU1_SA_DQS_DN<8>")
		)
		(pad "190" smd rect
			(at 2.050034 -25.07488 90)
			(size 0.519938 1.4986)
			(layers "F.Cu" "F.Mask" "F.Paste")
			(net "M_D_CPU1_SA_DQS_DP<8>")
		)
		(pad "191" smd rect
			(at 2.050034 -24.224996 90)
			(size 0.519938 1.4986)
			(layers "F.Cu" "F.Mask" "F.Paste")
			(net "GND")
		)
		(pad "192" smd rect
			(at 2.050034 -23.375112 90)
			(size 0.519938 1.4986)
			(layers "F.Cu" "F.Mask" "F.Paste")
			(net "M_D_CPU1_SA_DQ<30>")
		)
		(pad "193" smd rect
			(at 2.050034 -22.524974 90)
			(size 0.519938 1.4986)
			(layers "F.Cu" "F.Mask" "F.Paste")
			(net "GND")
		)
		(pad "194" smd rect
			(at 2.050034 -21.67509 90)
			(size 0.519938 1.4986)
			(layers "F.Cu" "F.Mask" "F.Paste")
			(net "M_D_CPU1_SA_DQ<31>")
		)
		(pad "195" smd rect
			(at 2.050034 -20.824952 90)
			(size 0.519938 1.4986)
			(layers "F.Cu" "F.Mask" "F.Paste")
			(net "GND")
		)
		(pad "196" smd rect
			(at 2.050034 -19.975068 90)
			(size 0.519938 1.4986)
			(layers "F.Cu" "F.Mask" "F.Paste")
			(net "M_D_CPU1_SA_CB<2>")
		)
		(pad "197" smd rect
			(at 2.050034 -19.12493 90)
			(size 0.519938 1.4986)
			(layers "F.Cu" "F.Mask" "F.Paste")
			(net "GND")
		)
		(pad "198" smd rect
			(at 2.050034 -18.275046 90)
			(size 0.519938 1.4986)
			(layers "F.Cu" "F.Mask" "F.Paste")
			(net "M_D_CPU1_SA_CB<3>")
		)
		(pad "199" smd rect
			(at 2.050034 -17.424908 90)
			(size 0.519938 1.4986)
			(layers "F.Cu" "F.Mask" "F.Paste")
			(net "GND")
		)
		(pad "200" smd rect
			(at 2.050034 -16.575024 90)
			(size 0.519938 1.4986)
			(layers "F.Cu" "F.Mask" "F.Paste")
			(net "M_D_CPU1_SA_DQS_DN<9>")
		)
		(pad "201" smd rect
			(at 2.050034 -15.724886 90)
			(size 0.519938 1.4986)
			(layers "F.Cu" "F.Mask" "F.Paste")
			(net "M_D_CPU1_SA_DQS_DP<9>")
		)
		(pad "202" smd rect
			(at 2.050034 -14.875002 90)
			(size 0.519938 1.4986)
			(layers "F.Cu" "F.Mask" "F.Paste")
			(net "GND")
		)
		(pad "203" smd rect
			(at 2.050034 -14.025118 90)
			(size 0.519938 1.4986)
			(layers "F.Cu" "F.Mask" "F.Paste")
			(net "M_D_CPU1_SA_CB<6>")
		)
		(pad "204" smd rect
			(at 2.050034 -13.17498 90)
			(size 0.519938 1.4986)
			(layers "F.Cu" "F.Mask" "F.Paste")
			(net "GND")
		)
		(pad "205" smd rect
			(at 2.050034 -12.325096 90)
			(size 0.519938 1.4986)
			(layers "F.Cu" "F.Mask" "F.Paste")
			(net "M_D_CPU1_SA_CB<7>")
		)
		(pad "206" smd rect
			(at 2.050034 -11.474958 90)
			(size 0.519938 1.4986)
			(layers "F.Cu" "F.Mask" "F.Paste")
			(net "GND")
		)
		(pad "207" smd rect
			(at 2.050034 -10.625074 90)
			(size 0.519938 1.4986)
			(layers "F.Cu" "F.Mask" "F.Paste")
			(net "M_D_CPU1_RESET_N")
		)
		(pad "208" smd rect
			(at 2.050034 -9.774936 90)
			(size 0.519938 1.4986)
			(layers "F.Cu" "F.Mask" "F.Paste")
			(net "GND")
		)
		(pad "209" smd rect
			(at 2.050034 -8.925052 90)
			(size 0.519938 1.4986)
			(layers "F.Cu" "F.Mask" "F.Paste")
			(net "M_D_CPU1_SA_CS_N<1>")
		)
		(pad "210" smd rect
			(at 2.050034 -8.074914 90)
			(size 0.519938 1.4986)
			(layers "F.Cu" "F.Mask" "F.Paste")
			(net "GND")
		)
		(pad "211" smd rect
			(at 2.050034 -7.22503 90)
			(size 0.519938 1.4986)
			(layers "F.Cu" "F.Mask" "F.Paste")
			(net "M_D_CPU1_SA_CA<1>")
		)
		(pad "212" smd rect
			(at 2.050034 -6.374892 90)
			(size 0.519938 1.4986)
			(layers "F.Cu" "F.Mask" "F.Paste")
			(net "GND")
		)
		(pad "213" smd rect
			(at 2.050034 -5.525008 90)
			(size 0.519938 1.4986)
			(layers "F.Cu" "F.Mask" "F.Paste")
			(net "M_D_CPU1_SA_CA<3>")
		)
		(pad "214" smd rect
			(at 2.050034 -4.675124 90)
			(size 0.519938 1.4986)
			(layers "F.Cu" "F.Mask" "F.Paste")
			(net "GND")
		)
		(pad "215" smd rect
			(at 2.050034 -3.824986 90)
			(size 0.519938 1.4986)
			(layers "F.Cu" "F.Mask" "F.Paste")
			(net "M_D_CPU1_SA_CA<5>")
		)
		(pad "216" smd rect
			(at 2.050034 -2.975102 90)
			(size 0.519938 1.4986)
			(layers "F.Cu" "F.Mask" "F.Paste")
			(net "GND")
		)
		(pad "217" smd rect
			(at 2.050034 -2.124964 90)
			(size 0.519938 1.4986)
			(layers "F.Cu" "F.Mask" "F.Paste")
			(net "M_D_CPU1_CLK_DP<0>")
		)
		(pad "218" smd rect
			(at 2.050034 -1.27508 90)
			(size 0.519938 1.4986)
			(layers "F.Cu" "F.Mask" "F.Paste")
			(net "M_D_CPU1_CLK_DN<0>")
		)
		(pad "219" smd rect
			(at 2.050034 -0.424942 90)
			(size 0.519938 1.4986)
			(layers "F.Cu" "F.Mask" "F.Paste")
			(net "GND")
		)
		(pad "220" smd rect
			(at 2.050034 5.525008 90)
			(size 0.519938 1.4986)
			(layers "F.Cu" "F.Mask" "F.Paste")
			(net "Net_2302")
		)
		(pad "221" smd rect
			(at 2.050034 6.374892 90)
			(size 0.519938 1.4986)
			(layers "F.Cu" "F.Mask" "F.Paste")
			(net "M_D_CPU1_SB_CA<1>")
		)
		(pad "222" smd rect
			(at 2.050034 7.22503 90)
			(size 0.519938 1.4986)
			(layers "F.Cu" "F.Mask" "F.Paste")
			(net "GND")
		)
		(pad "223" smd rect
			(at 2.050034 8.074914 90)
			(size 0.519938 1.4986)
			(layers "F.Cu" "F.Mask" "F.Paste")
			(net "M_D_CPU1_SB_CA<3>")
		)
		(pad "224" smd rect
			(at 2.050034 8.925052 90)
			(size 0.519938 1.4986)
			(layers "F.Cu" "F.Mask" "F.Paste")
			(net "GND")
		)
		(pad "225" smd rect
			(at 2.050034 9.774936 90)
			(size 0.519938 1.4986)
			(layers "F.Cu" "F.Mask" "F.Paste")
			(net "M_D_CPU1_SB_CA<5>")
		)
		(pad "226" smd rect
			(at 2.050034 10.625074 90)
			(size 0.519938 1.4986)
			(layers "F.Cu" "F.Mask" "F.Paste")
			(net "GND")
		)
	)
)
